# BASEBOARD_FAB2 (Tioga Pass) — schematic netlist excerpt (pin names and nets, part order shuffled) for the footprints in the layout excerpt that follows; sources: Cadence DE-HDL packaged netlist, KiCad conversion of Wiwynn_Tioga_Pass_MB.brd

CF11  SC22P50V2JN-4GP  5%  pkg SMD-BCG  page 206 : \1\ = VR_PVCCIN_CPU1_AIREF5 ; \2\ = ISENSE_PVCCIN_CPU1_PH5_IMON
C4C10  CAP_A  0.1UF 16V 10% X7R  pkg 0402V  page 205 : A = VR_FET_SW_P12V_STBY_PVCCIN_CPU0 ; B = GND
R25W47  120R2F-GP  1%  pkg RCL_GP  page 151 : \1\ = BMC_M_A9 ; \2\ = P1V2_AUX_BMC

(kicad_pcb
	(version 20260206)
	(generator "pcbnew")
	(generator_version "10.0")
	(general
		(thickness 1.6)
		(legacy_teardrops no)
	)
	(paper "A4")
	(title_block
		(title "Wiwynn_Tioga_Pass_MB.brd")
		(comment 1 "Tioga Pass / footprints 1381-1383 of 4770")
	)
	(layers
		(0 "F.Cu" signal "TOP")
		(4 "In1.Cu" signal "L2GND")
		(6 "In2.Cu" signal "L3")
		(8 "In3.Cu" signal "L4GND")
		(10 "In4.Cu" signal "L5")
		(12 "In5.Cu" signal "L6GND")
		(14 "In6.Cu" signal "L7VCC")
		(16 "In7.Cu" signal "L8VCC")
		(18 "In8.Cu" signal "L9GND")
		(20 "In9.Cu" signal "L10")
		(22 "In10.Cu" signal "L11GND")
		(24 "In11.Cu" signal "L12")
		(26 "In12.Cu" signal "L13GND")
		(2 "B.Cu" signal "BOTTOM")
		(9 "F.Adhes" user "F.Adhesive")
		(11 "B.Adhes" user "B.Adhesive")
		(13 "F.Paste" user "Package Geometry/Pastemask Top")
		(15 "B.Paste" user "Package Geometry/Pastemask Bottom")
		(5 "F.SilkS" user "Ref Des/Silkscreen Top")
		(7 "B.SilkS" user "Ref Des/Silkscreen Bottom")
		(1 "F.Mask" user "Board Geometry/Soldermask Top")
		(3 "B.Mask" user "Board Geometry/Soldermask Bottom")
		(17 "Dwgs.User" user "User.Drawings")
		(19 "Cmts.User" user "User.Comments")
		(21 "Eco1.User" user "User.Eco1")
		(23 "Eco2.User" user "User.Eco2")
		(25 "Edge.Cuts" user "Board Geometry/Outline")
		(27 "Margin" user)
		(31 "F.CrtYd" user "Package Geometry/Place Bound Top")
		(29 "B.CrtYd" user "Package Geometry/Place Bound Bottom")
		(35 "F.Fab" user "Ref Des/Assembly Top")
		(33 "B.Fab" user "Ref Des/Assembly Bottom")
	)
	(footprint ""
		(layer "F.Cu")
		(at 25.04186 -93.8911 180)
		(property "Reference" "CF11"
			(at 0 0 180)
			(layer "F.SilkS")
			(hide yes)
			(effects
				(font
					(size 1.27 1.27)
				)
			)
		)
		(property "Value" "*"
			(at 1.1811 -2.8194 180)
			(unlocked yes)
			(layer "F.Fab")
			(hide yes)
			(effects
				(font
					(size 1.27 1.016)
					(thickness 0.1524)
				)
			)
		)
		(property "Device Type" "SC22P50V2JN-4GP_SMD-BCG-SC22P5A"
			(at 1.1811 -4.3434 180)
			(unlocked yes)
			(layer "F.Fab")
			(hide yes)
			(effects
				(font
					(size 1.27 1.016)
					(thickness 0.1524)
				)
			)
		)
		(duplicate_pad_numbers_are_jumpers no)
		(fp_rect
			(start -0.4318 0.9525)
			(end 0.4318 -0.9525)
			(stroke
				(width 0)
				(type default)
			)
			(fill no)
			(layer "F.CrtYd")
		)
		(fp_rect
			(start -0.4318 0.9525)
			(end 0.4318 -0.9525)
			(stroke
				(width 0)
				(type default)
			)
			(fill no)
			(layer "F.Fab")
		)
		(pad "1" smd custom
			(at 0 -0.4445 180)
			(size 0.1524 0.1524)
			(layers "F.Cu" "F.Mask" "F.Paste")
			(net "VR_PVCCIN_CPU1_AIREF5")
			(options
				(clearance outline)
				(anchor circle)
			)
			(primitives
				(gr_poly
					(pts
						(arc
							(start 0.3048 -0.2032)
							(mid 0.275042 -0.275042)
							(end 0.2032 -0.3048)
						)
						(arc
							(start -0.2032 -0.3048)
							(mid -0.275042 -0.275042)
							(end -0.3048 -0.2032)
						)
						(arc
							(start -0.3048 0.2032)
							(mid -0.275042 0.275042)
							(end -0.2032 0.3048)
						)
						(arc
							(start 0.2032 0.3048)
							(mid 0.275042 0.275042)
							(end 0.3048 0.2032)
						)
					)
					(width 0)
					(fill yes)
				)
			)
		)
		(pad "2" smd custom
			(at 0 0.4445 180)
			(size 0.1524 0.1524)
			(layers "F.Cu" "F.Mask" "F.Paste")
			(net "ISENSE_PVCCIN_CPU1_PH5_IMON")
			(options
				(clearance outline)
				(anchor circle)
			)
			(primitives
				(gr_poly
					(pts
						(arc
							(start 0.3048 -0.2032)
							(mid 0.275042 -0.275042)
							(end 0.2032 -0.3048)
						)
						(arc
							(start -0.2032 -0.3048)
							(mid -0.275042 -0.275042)
							(end -0.3048 -0.2032)
						)
						(arc
							(start -0.3048 0.2032)
							(mid -0.275042 0.275042)
							(end -0.2032 0.3048)
						)
						(arc
							(start 0.2032 0.3048)
							(mid 0.275042 0.275042)
							(end 0.3048 0.2032)
						)
					)
					(width 0)
					(fill yes)
				)
			)
		)
	)
	(footprint ""
		(layer "F.Cu")
		(at 438.833006 -43.568874 180)
		(property "Reference" "R25W47"
			(at 0 0 180)
			(layer "F.SilkS")
			(hide yes)
			(effects
				(font
					(size 1.27 1.27)
				)
			)
		)
		(property "Value" "*"
			(at 0.064008 -4.108196 180)
			(unlocked yes)
			(layer "F.Fab")
			(hide yes)
			(effects
				(font
					(size 1.27 1.016)
					(thickness 0.1524)
				)
			)
		)
		(property "Device Type" "120R2F-GP_RCL_GP-120R2F-GP,64.A"
			(at 0.064008 -5.632196 180)
			(unlocked yes)
			(layer "F.Fab")
			(hide yes)
			(effects
				(font
					(size 1.27 1.016)
					(thickness 0.1524)
				)
			)
		)
		(duplicate_pad_numbers_are_jumpers no)
		(fp_line
			(start 0.508 -0.9398)
			(end -0.508 -0.9398)
			(stroke
				(width 0.1524)
				(type default)
			)
			(layer "F.SilkS")
		)
		(fp_line
			(start -0.508 -0.9398)
			(end -0.508 0.9398)
			(stroke
				(width 0.1524)
				(type default)
			)
			(layer "F.SilkS")
		)
		(fp_rect
			(start -0.508 0.9398)
			(end 0.508 -0.9398)
			(stroke
				(width 0)
				(type default)
			)
			(fill no)
			(layer "F.CrtYd")
		)
		(fp_rect
			(start -0.508 0.9398)
			(end 0.508 -0.9398)
			(stroke
				(width 0)
				(type default)
			)
			(fill no)
			(layer "F.Fab")
		)
		(pad "1" smd custom
			(at 0 -0.4445 180)
			(size 0.1397 0.1397)
			(layers "F.Cu" "F.Mask" "F.Paste")
			(net "BMC_M_A9")
			(options
				(clearance outline)
				(anchor circle)
			)
			(primitives
				(gr_poly
					(pts
						(arc
							(start -0.1778 -0.2794)
							(mid -0.249642 -0.249642)
							(end -0.2794 -0.1778)
						)
						(arc
							(start -0.2794 0.1778)
							(mid -0.249642 0.249642)
							(end -0.1778 0.2794)
						)
						(arc
							(start 0.1778 0.2794)
							(mid 0.249642 0.249642)
							(end 0.2794 0.1778)
						)
						(arc
							(start 0.2794 -0.1778)
							(mid 0.249642 -0.249642)
							(end 0.1778 -0.2794)
						)
					)
					(width 0)
					(fill yes)
				)
			)
		)
		(pad "2" smd custom
			(at 0 0.4445 180)
			(size 0.1397 0.1397)
			(layers "F.Cu" "F.Mask" "F.Paste")
			(net "P1V2_AUX_BMC")
			(options
				(clearance outline)
				(anchor circle)
			)
			(primitives
				(gr_poly
					(pts
						(arc
							(start -0.1778 -0.2794)
							(mid -0.249642 -0.249642)
							(end -0.2794 -0.1778)
						)
						(arc
							(start -0.2794 0.1778)
							(mid -0.249642 0.249642)
							(end -0.1778 0.2794)
						)
						(arc
							(start 0.1778 0.2794)
							(mid 0.249642 0.249642)
							(end 0.2794 0.1778)
						)
						(arc
							(start 0.2794 -0.1778)
							(mid 0.249642 -0.249642)
							(end 0.1778 -0.2794)
						)
					)
					(width 0)
					(fill yes)
				)
			)
		)
	)
	(footprint ""
		(layer "F.Cu")
		(at 198.370444 -102.053136 90)
		(property "Reference" "C4C10"
			(at 0 0 90)
			(layer "F.SilkS")
			(hide yes)
			(effects
				(font
					(size 1.27 1.27)
				)
			)
		)
		(property "Value" ""
			(at 0 0 90)
			(layer "F.Fab")
			(effects
				(font
					(size 1.27 1.27)
				)
			)
		)
		(duplicate_pad_numbers_are_jumpers no)
		(fp_rect
			(start 0.3048 0.9906)
			(end -0.3048 -0.1016)
			(stroke
				(width 0)
				(type default)
			)
			(fill no)
			(layer "F.CrtYd")
		)
		(fp_line
			(start 0.3048 -0.1016)
			(end -0.3048 -0.1016)
			(stroke
				(width 0.1)
				(type default)
			)
			(layer "F.Fab")
		)
		(fp_line
			(start -0.3048 -0.1016)
			(end -0.3048 0.9906)
			(stroke
				(width 0.1)
				(type default)
			)
			(layer "F.Fab")
		)
		(fp_line
			(start 0.3048 0.9906)
			(end 0.3048 -0.1016)
			(stroke
				(width 0.1)
				(type default)
			)
			(layer "F.Fab")
		)
		(fp_line
			(start -0.3048 0.9906)
			(end 0.3048 0.9906)
			(stroke
				(width 0.1)
				(type default)
			)
			(layer "F.Fab")
		)
		(pad "1" smd rect
			(at 0 0 90)
			(size 0.508 0.508)
			(layers "F.Cu" "F.Mask" "F.Paste")
			(net "VR_FET_SW_P12V_STBY_PVCCIN_CPU0")
		)
		(pad "2" smd rect
			(at 0 0.889 90)
			(size 0.508 0.508)
			(layers "F.Cu" "F.Mask" "F.Paste")
			(net "GND")
		)
		(zone
			(layer "F.Cu")
			(hatch none 0.5)
			(connect_pads
				(clearance 0)
			)
			(min_thickness 0.25)
			(keepout
				(tracks allowed)
				(vias not_allowed)
				(pads allowed)
				(copperpour not_allowed)
				(footprints allowed)
			)
			(placement
				(enabled no)
				(sheetname "")
			)
			(fill
				(thermal_gap 0.5)
				(thermal_bridge_width 0.5)
				(island_removal_mode 0)
			)
			(polygon
				(pts
					(xy 199.005444 -102.307136) (xy 198.624444 -102.307136) (xy 198.624444 -101.799136) (xy 199.005444 -101.799136)
				)
			)
		)
		(zone
			(layer "F.Cu")
			(hatch none 0.5)
			(connect_pads
				(clearance 0)
			)
			(min_thickness 0.25)
			(keepout
				(tracks not_allowed)
				(vias allowed)
				(pads allowed)
				(copperpour not_allowed)
				(footprints allowed)
			)
			(placement
				(enabled no)
				(sheetname "")
			)
			(fill
				(thermal_gap 0.5)
				(thermal_bridge_width 0.5)
				(island_removal_mode 0)
			)
			(polygon
				(pts
					(xy 199.005444 -102.307136) (xy 198.624444 -102.307136) (xy 198.624444 -101.799136) (xy 199.005444 -101.799136)
				)
			)
		)
	)
)
